# BASEBOARD_FAB2 (Tioga Pass) — schematic netlist excerpt (pin names and nets, part order shuffled) for the footprints in the layout excerpt that follows; sources: Cadence DE-HDL packaged netlist, KiCad conversion of Wiwynn_Tioga_Pass_MB.brd

EU1D3  IR354XX  IR35411 IC  pkg SM  page 208
  VOS  = PVCCIN_CPU1
  LGND  = GND
  VCC  = VR_PVCCIN_CPU1_PH3_VCIN
  VDRV  = P5V_STBY
  PGND(0)  = GND
  GL(0)  = TP_PVCCIN_CPU1_PH3_GL_0
  PGND(1)  = GND
  SW  = VR_PVCCIN_CPU1_PHASE3
  VIN(0)  = VR_FET_SW_P12V_STBY_PVCCIN_CPU1
  VIN(1)  = VR_FET_SW_P12V_STBY_PVCCIN_CPU1
  NC  = NC
  PHASE  = VR_PVCCIN_CPU1_PH3_PHASE
  BOOST  = VR_PVCCIN_CPU1_PH3_BOOT_R
  PWM  = VR_PVCCIN_CPU1_PWM3
  EN  = P5V_STBY
  TOUT_FLT  = A_TSENSE_PVCCIN_CPU1
  OCSET  = VR_PVCCIN_CPU1_PH3_OCSET
  IOUT  = ISENSE_PVCCIN_CPU1_PH3_IMON
  REFIN  = VR_PVCCIN_CPU1_AIREF3
  PGND(2)  = GND
  GL(1)  = TP_PVCCIN_CPU1_PH3_GL_1

(kicad_pcb
	(version 20260206)
	(generator "pcbnew")
	(generator_version "10.0")
	(general
		(thickness 1.6)
		(legacy_teardrops no)
	)
	(paper "A4")
	(title_block
		(title "Wiwynn_Tioga_Pass_MB.brd")
		(comment 1 "Tioga Pass / footprints 448-448 of 4770")
	)
	(layers
		(0 "F.Cu" signal "TOP")
		(4 "In1.Cu" signal "L2GND")
		(6 "In2.Cu" signal "L3")
		(8 "In3.Cu" signal "L4GND")
		(10 "In4.Cu" signal "L5")
		(12 "In5.Cu" signal "L6GND")
		(14 "In6.Cu" signal "L7VCC")
		(16 "In7.Cu" signal "L8VCC")
		(18 "In8.Cu" signal "L9GND")
		(20 "In9.Cu" signal "L10")
		(22 "In10.Cu" signal "L11GND")
		(24 "In11.Cu" signal "L12")
		(26 "In12.Cu" signal "L13GND")
		(2 "B.Cu" signal "BOTTOM")
		(9 "F.Adhes" user "F.Adhesive")
		(11 "B.Adhes" user "B.Adhesive")
		(13 "F.Paste" user "Package Geometry/Pastemask Top")
		(15 "B.Paste" user "Package Geometry/Pastemask Bottom")
		(5 "F.SilkS" user "Ref Des/Silkscreen Top")
		(7 "B.SilkS" user "Ref Des/Silkscreen Bottom")
		(1 "F.Mask" user "Board Geometry/Soldermask Top")
		(3 "B.Mask" user "Board Geometry/Soldermask Bottom")
		(17 "Dwgs.User" user "User.Drawings")
		(19 "Cmts.User" user "User.Comments")
		(21 "Eco1.User" user "User.Eco1")
		(23 "Eco2.User" user "User.Eco2")
		(25 "Edge.Cuts" user "Board Geometry/Outline")
		(27 "Margin" user)
		(31 "F.CrtYd" user "Package Geometry/Place Bound Top")
		(29 "B.CrtYd" user "Package Geometry/Place Bound Bottom")
		(35 "F.Fab" user "Ref Des/Assembly Top")
		(33 "B.Fab" user "Ref Des/Assembly Bottom")
	)
	(footprint ""
		(layer "F.Cu")
		(at 33.925002 -73.295764 90)
		(property "Reference" "EU1D3"
			(at 2.420366 5.267198 0)
			(unlocked yes)
			(layer "F.SilkS")
			(effects
				(font
					(size 0.7874 0.5842)
					(thickness 0.1524)
				)
			)
		)
		(property "Value" ""
			(at 0 0 90)
			(layer "F.Fab")
			(effects
				(font
					(size 1.27 1.27)
				)
			)
		)
		(duplicate_pad_numbers_are_jumpers no)
		(fp_line
			(start 2.9718 -3.5052)
			(end 2.9718 3.429)
			(stroke
				(width 0.1524)
				(type default)
			)
			(layer "F.SilkS")
		)
		(fp_line
			(start -3.0099 -3.5052)
			(end 2.9718 -3.5052)
			(stroke
				(width 0.1524)
				(type default)
			)
			(layer "F.SilkS")
		)
		(fp_line
			(start 2.9718 3.429)
			(end -3.0099 3.429)
			(stroke
				(width 0.1524)
				(type default)
			)
			(layer "F.SilkS")
		)
		(fp_line
			(start -3.0099 3.429)
			(end -3.0099 -3.5052)
			(stroke
				(width 0.1524)
				(type default)
			)
			(layer "F.SilkS")
		)
		(fp_circle
			(center -3.057398 -2.678684)
			(end -3.057398 -2.551684)
			(stroke
				(width 0.254)
				(type default)
			)
			(fill no)
			(layer "F.SilkS")
		)
		(fp_poly
			(pts
				(xy -2.9972 -3.4925) (xy -2.9972 -2.6924) (xy -2.1971 -3.4925)
			)
			(stroke
				(width 0)
				(type default)
			)
			(fill yes)
			(layer "F.SilkS")
		)
		(fp_poly
			(pts
				(xy -2.549906 -3.050032) (xy -2.549906 3.050032) (xy 2.549906 3.050032) (xy 2.549906 -3.050032)
			)
			(stroke
				(width 0)
				(type default)
			)
			(fill no)
			(layer "F.CrtYd")
		)
		(fp_line
			(start 2.549906 -3.050032)
			(end 2.549906 3.050032)
			(stroke
				(width 0.1)
				(type default)
			)
			(layer "F.Fab")
		)
		(fp_line
			(start -2.549906 -3.050032)
			(end 2.549906 -3.050032)
			(stroke
				(width 0.1)
				(type default)
			)
			(layer "F.Fab")
		)
		(fp_line
			(start 2.549906 3.050032)
			(end -2.549906 3.050032)
			(stroke
				(width 0.1)
				(type default)
			)
			(layer "F.Fab")
		)
		(fp_line
			(start -2.549906 3.050032)
			(end -2.549906 -3.050032)
			(stroke
				(width 0.1)
				(type default)
			)
			(layer "F.Fab")
		)
		(fp_circle
			(center -3.057398 -2.678684)
			(end -3.057398 -2.551684)
			(stroke
				(width 0.254)
				(type default)
			)
			(fill no)
			(layer "F.Fab")
		)
		(pad "1" smd rect
			(at -2.39522 -2.279904 90)
			(size 0.7112 0.254)
			(layers "F.Cu" "F.Mask" "F.Paste")
			(net "PVCCIN_CPU1")
		)
		(pad "2" smd rect
			(at -2.39522 -1.83007 90)
			(size 0.7112 0.254)
			(layers "F.Cu" "F.Mask" "F.Paste")
			(net "GND")
		)
		(pad "3" smd rect
			(at -2.39522 -1.379982 90)
			(size 0.7112 0.254)
			(layers "F.Cu" "F.Mask" "F.Paste")
			(net "VR_PVCCIN_CPU1_PH3_VCIN")
		)
		(pad "4" smd rect
			(at -2.39522 -0.929894 90)
			(size 0.7112 0.254)
			(layers "F.Cu" "F.Mask" "F.Paste")
			(net "P5V_STBY")
		)
		(pad "5" smd rect
			(at -2.39522 -0.48006 90)
			(size 0.7112 0.254)
			(layers "F.Cu" "F.Mask" "F.Paste")
			(net "GND")
		)
		(pad "6" smd rect
			(at -2.39522 -0.029972 90)
			(size 0.7112 0.254)
			(layers "F.Cu" "F.Mask" "F.Paste")
			(net "TP_PVCCIN_CPU1_PH3_GL_0")
		)
		(pad "7" smd custom
			(at 0.016764 1.145032 90)
			(size 0.53975 0.53975)
			(layers "F.Cu" "F.Mask" "F.Paste")
			(net "GND")
			(options
				(clearance outline)
				(anchor circle)
			)
			(primitives
				(gr_poly
					(pts
						(xy -2.7051 1.0795) (xy -2.7051 -0.3683) (xy -0.9271 -0.3683) (xy -0.9271 -1.0795) (xy 2.7051 -1.0795)
						(xy 2.7051 1.0795)
					)
					(width 0)
					(fill yes)
				)
			)
		)
		(pad "10" smd rect
			(at -0.008382 2.874772 90)
			(size 4.3434 0.6096)
			(layers "F.Cu" "F.Mask" "F.Paste")
			(net "VR_PVCCIN_CPU1_PHASE3")
		)
		(pad "25" smd rect
			(at 1.548384 -1.283208 90)
			(size 2.3368 2.0066)
			(layers "F.Cu" "F.Mask" "F.Paste")
			(net "VR_FET_SW_P12V_STBY_PVCCIN_CPU1")
		)
		(pad "30" smd rect
			(at 2.050034 -2.895092 90)
			(size 0.254 0.7112)
			(layers "F.Cu" "F.Mask" "F.Paste")
			(net "VR_FET_SW_P12V_STBY_PVCCIN_CPU1")
		)
		(pad "31" smd rect
			(at 1.599946 -2.895092 90)
			(size 0.254 0.7112)
			(layers "F.Cu" "F.Mask" "F.Paste")
			(net "Net_294")
		)
		(pad "32" smd rect
			(at 1.150112 -2.895092 90)
			(size 0.254 0.7112)
			(layers "F.Cu" "F.Mask" "F.Paste")
			(net "VR_PVCCIN_CPU1_PH3_PHASE")
		)
		(pad "33" smd rect
			(at 0.700024 -2.895092 90)
			(size 0.254 0.7112)
			(layers "F.Cu" "F.Mask" "F.Paste")
			(net "VR_PVCCIN_CPU1_PH3_BOOT_R")
		)
		(pad "34" smd rect
			(at 0.249936 -2.895092 90)
			(size 0.254 0.7112)
			(layers "F.Cu" "F.Mask" "F.Paste")
			(net "VR_PVCCIN_CPU1_PWM3")
		)
		(pad "35" smd rect
			(at -0.199898 -2.895092 90)
			(size 0.254 0.7112)
			(layers "F.Cu" "F.Mask" "F.Paste")
			(net "P5V_STBY")
		)
		(pad "36" smd rect
			(at -0.649986 -2.895092 90)
			(size 0.254 0.7112)
			(layers "F.Cu" "F.Mask" "F.Paste")
			(net "A_TSENSE_PVCCIN_CPU1")
		)
		(pad "37" smd rect
			(at -1.100074 -2.895092 90)
			(size 0.254 0.7112)
			(layers "F.Cu" "F.Mask" "F.Paste")
			(net "VR_PVCCIN_CPU1_PH3_OCSET")
		)
		(pad "38" smd rect
			(at -1.549908 -2.895092 90)
			(size 0.254 0.7112)
			(layers "F.Cu" "F.Mask" "F.Paste")
			(net "ISENSE_PVCCIN_CPU1_PH3_IMON")
		)
		(pad "39" smd rect
			(at -1.999996 -2.895092 90)
			(size 0.254 0.7112)
			(layers "F.Cu" "F.Mask" "F.Paste")
			(net "VR_PVCCIN_CPU1_AIREF3")
		)
		(pad "40" smd rect
			(at -0.871728 -1.283208 90)
			(size 1.8034 2.0066)
			(layers "F.Cu" "F.Mask" "F.Paste")
			(net "GND")
		)
		(pad "41" smd rect
			(at -1.533906 0.247904 90)
			(size 0.508 0.3556)
			(layers "F.Cu" "F.Mask" "F.Paste")
			(net "TP_PVCCIN_CPU1_PH3_GL_1")
		)
	)
)
